# S9S_MB_2U (Grand Teton) — schematic netlist excerpt (pin names and nets, part order shuffled) for the footprints in the layout excerpt that follows; sources: Cadence DE-HDL packaged netlist, KiCad conversion of 03242023_DA0F0TMBIJ0_F0T_Motherboard_J_brd_V01_OCP.brd

R3623  Q_RES  4.7K 1% CHIP  pkg 0402LF  page 172 : A = P3V3_AUX ; B = INA230_4_A1
R3499  Q_RES  0 5% CHIP  pkg 0402LF  page 227 : A = GPU_BASE_ID1 ; B = GPU_BASE_ID1_R

(kicad_pcb
	(version 20260206)
	(generator "pcbnew")
	(generator_version "10.0")
	(general
		(thickness 1.6)
		(legacy_teardrops no)
	)
	(paper "A4")
	(title_block
		(title "03242023_DA0F0TMBIJ0_F0T_Motherboard_J_brd_V01_OCP.brd")
		(comment 1 "Grand Teton / footprints 3726-3727 of 6105")
	)
	(layers
		(0 "F.Cu" signal "TOP")
		(4 "In1.Cu" signal "GND")
		(6 "In2.Cu" signal "IN1")
		(8 "In3.Cu" signal "GND1")
		(10 "In4.Cu" signal "IN2")
		(12 "In5.Cu" signal "GND2")
		(14 "In6.Cu" signal "IN3")
		(16 "In7.Cu" signal "GND3")
		(18 "In8.Cu" signal "VCC")
		(20 "In9.Cu" signal "VCC1")
		(22 "In10.Cu" signal "GND4")
		(24 "In11.Cu" signal "IN4")
		(26 "In12.Cu" signal "GND5")
		(28 "In13.Cu" signal "IN5")
		(30 "In14.Cu" signal "GND6")
		(32 "In15.Cu" signal "IN6")
		(34 "In16.Cu" signal "GND7")
		(2 "B.Cu" signal "BOTTOM")
		(9 "F.Adhes" user "F.Adhesive")
		(11 "B.Adhes" user "B.Adhesive")
		(13 "F.Paste" user "Package Geometry/Pastemask Top")
		(15 "B.Paste" user "Package Geometry/Pastemask Bottom")
		(5 "F.SilkS" user "Ref Des/Silkscreen Top")
		(7 "B.SilkS" user "Ref Des/Silkscreen Bottom")
		(1 "F.Mask" user "Board Geometry/Soldermask Top")
		(3 "B.Mask" user "Board Geometry/Soldermask Bottom")
		(17 "Dwgs.User" user "User.Drawings")
		(19 "Cmts.User" user "User.Comments")
		(21 "Eco1.User" user "User.Eco1")
		(23 "Eco2.User" user "User.Eco2")
		(25 "Edge.Cuts" user "Board Geometry/Outline")
		(27 "Margin" user)
		(31 "F.CrtYd" user "Package Geometry/Place Bound Top")
		(29 "B.CrtYd" user "Package Geometry/Place Bound Bottom")
		(35 "F.Fab" user "Ref Des/Assembly Top")
		(33 "B.Fab" user "Ref Des/Assembly Bottom")
	)
	(footprint ""
		(layer "F.Cu")
		(at 148.197824 -52.420012)
		(property "Reference" "R3623"
			(at 0 0 0)
			(layer "F.SilkS")
			(hide yes)
			(effects
				(font
					(size 1.27 1.27)
				)
			)
		)
		(property "Value" ""
			(at 0 0 0)
			(layer "F.Fab")
			(effects
				(font
					(size 1.27 1.27)
				)
			)
		)
		(duplicate_pad_numbers_are_jumpers no)
		(fp_line
			(start -0.7874 -0.4064)
			(end 0.7874 -0.4064)
			(stroke
				(width 0.1524)
				(type default)
			)
			(layer "F.SilkS")
		)
		(fp_line
			(start -0.7874 0.4064)
			(end -0.7874 -0.4064)
			(stroke
				(width 0.1524)
				(type default)
			)
			(layer "F.SilkS")
		)
		(fp_line
			(start 0.7874 -0.4064)
			(end 0.7874 0.4064)
			(stroke
				(width 0.1524)
				(type default)
			)
			(layer "F.SilkS")
		)
		(fp_line
			(start 0.7874 0.4064)
			(end -0.7874 0.4064)
			(stroke
				(width 0.1524)
				(type default)
			)
			(layer "F.SilkS")
		)
		(fp_line
			(start -0.67945 -0.305054)
			(end -0.12065 -0.305054)
			(stroke
				(width 0.1)
				(type default)
			)
			(layer "F.Fab")
		)
		(fp_line
			(start -0.67945 0.3048)
			(end -0.67945 -0.305054)
			(stroke
				(width 0.1)
				(type default)
			)
			(layer "F.Fab")
		)
		(fp_line
			(start -0.12065 -0.305054)
			(end -0.12065 -0.2794)
			(stroke
				(width 0.1)
				(type default)
			)
			(layer "F.Fab")
		)
		(fp_line
			(start -0.12065 -0.2794)
			(end 0.12065 -0.2794)
			(stroke
				(width 0.1)
				(type default)
			)
			(layer "F.Fab")
		)
		(fp_line
			(start -0.12065 0.2794)
			(end -0.12065 0.3048)
			(stroke
				(width 0.1)
				(type default)
			)
			(layer "F.Fab")
		)
		(fp_line
			(start -0.12065 0.3048)
			(end -0.67945 0.3048)
			(stroke
				(width 0.1)
				(type default)
			)
			(layer "F.Fab")
		)
		(fp_line
			(start 0.120396 0.2794)
			(end -0.12065 0.2794)
			(stroke
				(width 0.1)
				(type default)
			)
			(layer "F.Fab")
		)
		(fp_line
			(start 0.120396 0.3048)
			(end 0.120396 0.2794)
			(stroke
				(width 0.1)
				(type default)
			)
			(layer "F.Fab")
		)
		(fp_line
			(start 0.12065 -0.3048)
			(end 0.67945 -0.3048)
			(stroke
				(width 0.1)
				(type default)
			)
			(layer "F.Fab")
		)
		(fp_line
			(start 0.12065 -0.2794)
			(end 0.12065 -0.3048)
			(stroke
				(width 0.1)
				(type default)
			)
			(layer "F.Fab")
		)
		(fp_line
			(start 0.67945 -0.3048)
			(end 0.67945 0.3048)
			(stroke
				(width 0.1)
				(type default)
			)
			(layer "F.Fab")
		)
		(fp_line
			(start 0.67945 0.3048)
			(end 0.120396 0.3048)
			(stroke
				(width 0.1)
				(type default)
			)
			(layer "F.Fab")
		)
		(pad "1" smd circle
			(at -0.40005 0)
			(size 0 0)
			(layers "F.Cu" "F.Mask" "F.Paste")
			(net "P3V3_AUX")
		)
		(pad "2" smd circle
			(at 0.40005 0)
			(size 0 0)
			(layers "F.Cu" "F.Mask" "F.Paste")
			(net "INA230_4_A1")
		)
	)
	(footprint ""
		(layer "F.Cu")
		(at 19.769582 -423.629836 -90)
		(property "Reference" "R3499"
			(at 0 0 270)
			(layer "F.SilkS")
			(hide yes)
			(effects
				(font
					(size 1.27 1.27)
				)
			)
		)
		(property "Value" ""
			(at 0 0 270)
			(layer "F.Fab")
			(effects
				(font
					(size 1.27 1.27)
				)
			)
		)
		(duplicate_pad_numbers_are_jumpers no)
		(fp_line
			(start -0.7874 0.4064)
			(end -0.7874 -0.4064)
			(stroke
				(width 0.1524)
				(type default)
			)
			(layer "F.SilkS")
		)
		(fp_line
			(start 0.7874 0.4064)
			(end -0.7874 0.4064)
			(stroke
				(width 0.1524)
				(type default)
			)
			(layer "F.SilkS")
		)
		(fp_line
			(start -0.7874 -0.4064)
			(end 0.7874 -0.4064)
			(stroke
				(width 0.1524)
				(type default)
			)
			(layer "F.SilkS")
		)
		(fp_line
			(start 0.7874 -0.4064)
			(end 0.7874 0.4064)
			(stroke
				(width 0.1524)
				(type default)
			)
			(layer "F.SilkS")
		)
		(fp_line
			(start -0.67945 0.3048)
			(end -0.67945 -0.305054)
			(stroke
				(width 0.1)
				(type default)
			)
			(layer "F.Fab")
		)
		(fp_line
			(start -0.12065 0.3048)
			(end -0.67945 0.3048)
			(stroke
				(width 0.1)
				(type default)
			)
			(layer "F.Fab")
		)
		(fp_line
			(start 0.120396 0.3048)
			(end 0.120396 0.2794)
			(stroke
				(width 0.1)
				(type default)
			)
			(layer "F.Fab")
		)
		(fp_line
			(start 0.67945 0.3048)
			(end 0.120396 0.3048)
			(stroke
				(width 0.1)
				(type default)
			)
			(layer "F.Fab")
		)
		(fp_line
			(start -0.12065 0.2794)
			(end -0.12065 0.3048)
			(stroke
				(width 0.1)
				(type default)
			)
			(layer "F.Fab")
		)
		(fp_line
			(start 0.120396 0.2794)
			(end -0.12065 0.2794)
			(stroke
				(width 0.1)
				(type default)
			)
			(layer "F.Fab")
		)
		(fp_line
			(start -0.12065 -0.2794)
			(end 0.12065 -0.2794)
			(stroke
				(width 0.1)
				(type default)
			)
			(layer "F.Fab")
		)
		(fp_line
			(start 0.12065 -0.2794)
			(end 0.12065 -0.3048)
			(stroke
				(width 0.1)
				(type default)
			)
			(layer "F.Fab")
		)
		(fp_line
			(start 0.12065 -0.3048)
			(end 0.67945 -0.3048)
			(stroke
				(width 0.1)
				(type default)
			)
			(layer "F.Fab")
		)
		(fp_line
			(start 0.67945 -0.3048)
			(end 0.67945 0.3048)
			(stroke
				(width 0.1)
				(type default)
			)
			(layer "F.Fab")
		)
		(fp_line
			(start -0.67945 -0.305054)
			(end -0.12065 -0.305054)
			(stroke
				(width 0.1)
				(type default)
			)
			(layer "F.Fab")
		)
		(fp_line
			(start -0.12065 -0.305054)
			(end -0.12065 -0.2794)
			(stroke
				(width 0.1)
				(type default)
			)
			(layer "F.Fab")
		)
		(pad "1" smd circle
			(at -0.40005 0 270)
			(size 0 0)
			(layers "F.Cu" "F.Mask" "F.Paste")
			(net "GPU_BASE_ID1")
		)
		(pad "2" smd circle
			(at 0.40005 0 270)
			(size 0 0)
			(layers "F.Cu" "F.Mask" "F.Paste")
			(net "GPU_BASE_ID1_R")
		)
	)
)
